# S9S_MB_2U (Grand Teton) — schematic netlist excerpt (pin names and nets, part order shuffled) for the footprints in the layout excerpt that follows; sources: Cadence DE-HDL packaged netlist, KiCad conversion of 03242023_DA0F0TMBIJ0_F0T_Motherboard_J_brd_V01_OCP.brd

R1320  Q_RES  1K 1% CHIP  pkg 0402LF  page 201 : A = P3V3_AUX ; B = PU_SWAP_OVERRIDE_N
R2940  Q_RES  4.7K 5% EMPTY  pkg 0402LF  page 246 : A = P3V3_AUX ; B = FM_GPU_HSC_EN

(kicad_pcb
	(version 20260206)
	(generator "pcbnew")
	(generator_version "10.0")
	(general
		(thickness 1.6)
		(legacy_teardrops no)
	)
	(paper "A4")
	(title_block
		(title "03242023_DA0F0TMBIJ0_F0T_Motherboard_J_brd_V01_OCP.brd")
		(comment 1 "Grand Teton / footprints 3607-3608 of 6105")
	)
	(layers
		(0 "F.Cu" signal "TOP")
		(4 "In1.Cu" signal "GND")
		(6 "In2.Cu" signal "IN1")
		(8 "In3.Cu" signal "GND1")
		(10 "In4.Cu" signal "IN2")
		(12 "In5.Cu" signal "GND2")
		(14 "In6.Cu" signal "IN3")
		(16 "In7.Cu" signal "GND3")
		(18 "In8.Cu" signal "VCC")
		(20 "In9.Cu" signal "VCC1")
		(22 "In10.Cu" signal "GND4")
		(24 "In11.Cu" signal "IN4")
		(26 "In12.Cu" signal "GND5")
		(28 "In13.Cu" signal "IN5")
		(30 "In14.Cu" signal "GND6")
		(32 "In15.Cu" signal "IN6")
		(34 "In16.Cu" signal "GND7")
		(2 "B.Cu" signal "BOTTOM")
		(9 "F.Adhes" user "F.Adhesive")
		(11 "B.Adhes" user "B.Adhesive")
		(13 "F.Paste" user "Package Geometry/Pastemask Top")
		(15 "B.Paste" user "Package Geometry/Pastemask Bottom")
		(5 "F.SilkS" user "Ref Des/Silkscreen Top")
		(7 "B.SilkS" user "Ref Des/Silkscreen Bottom")
		(1 "F.Mask" user "Board Geometry/Soldermask Top")
		(3 "B.Mask" user "Board Geometry/Soldermask Bottom")
		(17 "Dwgs.User" user "User.Drawings")
		(19 "Cmts.User" user "User.Comments")
		(21 "Eco1.User" user "User.Eco1")
		(23 "Eco2.User" user "User.Eco2")
		(25 "Edge.Cuts" user "Board Geometry/Outline")
		(27 "Margin" user)
		(31 "F.CrtYd" user "Package Geometry/Place Bound Top")
		(29 "B.CrtYd" user "Package Geometry/Place Bound Bottom")
		(35 "F.Fab" user "Ref Des/Assembly Top")
		(33 "B.Fab" user "Ref Des/Assembly Bottom")
	)
	(footprint ""
		(layer "F.Cu")
		(at 435.185566 -41.1226 180)
		(property "Reference" "R1320"
			(at 0 0 180)
			(layer "F.SilkS")
			(hide yes)
			(effects
				(font
					(size 1.27 1.27)
				)
			)
		)
		(property "Value" ""
			(at 0 0 180)
			(layer "F.Fab")
			(effects
				(font
					(size 1.27 1.27)
				)
			)
		)
		(duplicate_pad_numbers_are_jumpers no)
		(fp_line
			(start 0.7874 0.4064)
			(end -0.7874 0.4064)
			(stroke
				(width 0.1524)
				(type default)
			)
			(layer "F.SilkS")
		)
		(fp_line
			(start 0.7874 -0.4064)
			(end 0.7874 0.4064)
			(stroke
				(width 0.1524)
				(type default)
			)
			(layer "F.SilkS")
		)
		(fp_line
			(start -0.7874 0.4064)
			(end -0.7874 -0.4064)
			(stroke
				(width 0.1524)
				(type default)
			)
			(layer "F.SilkS")
		)
		(fp_line
			(start -0.7874 -0.4064)
			(end 0.7874 -0.4064)
			(stroke
				(width 0.1524)
				(type default)
			)
			(layer "F.SilkS")
		)
		(fp_line
			(start 0.67945 0.3048)
			(end 0.120396 0.3048)
			(stroke
				(width 0.1)
				(type default)
			)
			(layer "F.Fab")
		)
		(fp_line
			(start 0.67945 -0.3048)
			(end 0.67945 0.3048)
			(stroke
				(width 0.1)
				(type default)
			)
			(layer "F.Fab")
		)
		(fp_line
			(start 0.12065 -0.2794)
			(end 0.12065 -0.3048)
			(stroke
				(width 0.1)
				(type default)
			)
			(layer "F.Fab")
		)
		(fp_line
			(start 0.12065 -0.3048)
			(end 0.67945 -0.3048)
			(stroke
				(width 0.1)
				(type default)
			)
			(layer "F.Fab")
		)
		(fp_line
			(start 0.120396 0.3048)
			(end 0.120396 0.2794)
			(stroke
				(width 0.1)
				(type default)
			)
			(layer "F.Fab")
		)
		(fp_line
			(start 0.120396 0.2794)
			(end -0.12065 0.2794)
			(stroke
				(width 0.1)
				(type default)
			)
			(layer "F.Fab")
		)
		(fp_line
			(start -0.12065 0.3048)
			(end -0.67945 0.3048)
			(stroke
				(width 0.1)
				(type default)
			)
			(layer "F.Fab")
		)
		(fp_line
			(start -0.12065 0.2794)
			(end -0.12065 0.3048)
			(stroke
				(width 0.1)
				(type default)
			)
			(layer "F.Fab")
		)
		(fp_line
			(start -0.12065 -0.2794)
			(end 0.12065 -0.2794)
			(stroke
				(width 0.1)
				(type default)
			)
			(layer "F.Fab")
		)
		(fp_line
			(start -0.12065 -0.305054)
			(end -0.12065 -0.2794)
			(stroke
				(width 0.1)
				(type default)
			)
			(layer "F.Fab")
		)
		(fp_line
			(start -0.67945 0.3048)
			(end -0.67945 -0.305054)
			(stroke
				(width 0.1)
				(type default)
			)
			(layer "F.Fab")
		)
		(fp_line
			(start -0.67945 -0.305054)
			(end -0.12065 -0.305054)
			(stroke
				(width 0.1)
				(type default)
			)
			(layer "F.Fab")
		)
		(pad "1" smd circle
			(at -0.40005 0 180)
			(size 0 0)
			(layers "F.Cu" "F.Mask" "F.Paste")
			(net "P3V3_AUX")
		)
		(pad "2" smd circle
			(at 0.40005 0 180)
			(size 0 0)
			(layers "F.Cu" "F.Mask" "F.Paste")
			(net "PU_SWAP_OVERRIDE_N")
		)
	)
	(footprint ""
		(layer "F.Cu")
		(at 192.877186 -438.17413 -90)
		(property "Reference" "R2940"
			(at 0 0 270)
			(layer "F.SilkS")
			(hide yes)
			(effects
				(font
					(size 1.27 1.27)
				)
			)
		)
		(property "Value" ""
			(at 0 0 270)
			(layer "F.Fab")
			(effects
				(font
					(size 1.27 1.27)
				)
			)
		)
		(duplicate_pad_numbers_are_jumpers no)
		(fp_line
			(start -0.7874 0.4064)
			(end -0.7874 -0.4064)
			(stroke
				(width 0.1524)
				(type default)
			)
			(layer "F.SilkS")
		)
		(fp_line
			(start 0.7874 0.4064)
			(end -0.7874 0.4064)
			(stroke
				(width 0.1524)
				(type default)
			)
			(layer "F.SilkS")
		)
		(fp_line
			(start -0.7874 -0.4064)
			(end 0.7874 -0.4064)
			(stroke
				(width 0.1524)
				(type default)
			)
			(layer "F.SilkS")
		)
		(fp_line
			(start 0.7874 -0.4064)
			(end 0.7874 0.4064)
			(stroke
				(width 0.1524)
				(type default)
			)
			(layer "F.SilkS")
		)
		(fp_line
			(start -0.67945 0.3048)
			(end -0.67945 -0.305054)
			(stroke
				(width 0.1)
				(type default)
			)
			(layer "F.Fab")
		)
		(fp_line
			(start -0.12065 0.3048)
			(end -0.67945 0.3048)
			(stroke
				(width 0.1)
				(type default)
			)
			(layer "F.Fab")
		)
		(fp_line
			(start 0.120396 0.3048)
			(end 0.120396 0.2794)
			(stroke
				(width 0.1)
				(type default)
			)
			(layer "F.Fab")
		)
		(fp_line
			(start 0.67945 0.3048)
			(end 0.120396 0.3048)
			(stroke
				(width 0.1)
				(type default)
			)
			(layer "F.Fab")
		)
		(fp_line
			(start -0.12065 0.2794)
			(end -0.12065 0.3048)
			(stroke
				(width 0.1)
				(type default)
			)
			(layer "F.Fab")
		)
		(fp_line
			(start 0.120396 0.2794)
			(end -0.12065 0.2794)
			(stroke
				(width 0.1)
				(type default)
			)
			(layer "F.Fab")
		)
		(fp_line
			(start -0.12065 -0.2794)
			(end 0.12065 -0.2794)
			(stroke
				(width 0.1)
				(type default)
			)
			(layer "F.Fab")
		)
		(fp_line
			(start 0.12065 -0.2794)
			(end 0.12065 -0.3048)
			(stroke
				(width 0.1)
				(type default)
			)
			(layer "F.Fab")
		)
		(fp_line
			(start 0.12065 -0.3048)
			(end 0.67945 -0.3048)
			(stroke
				(width 0.1)
				(type default)
			)
			(layer "F.Fab")
		)
		(fp_line
			(start 0.67945 -0.3048)
			(end 0.67945 0.3048)
			(stroke
				(width 0.1)
				(type default)
			)
			(layer "F.Fab")
		)
		(fp_line
			(start -0.67945 -0.305054)
			(end -0.12065 -0.305054)
			(stroke
				(width 0.1)
				(type default)
			)
			(layer "F.Fab")
		)
		(fp_line
			(start -0.12065 -0.305054)
			(end -0.12065 -0.2794)
			(stroke
				(width 0.1)
				(type default)
			)
			(layer "F.Fab")
		)
		(pad "1" smd circle
			(at -0.40005 0 270)
			(size 0 0)
			(layers "F.Cu" "F.Mask" "F.Paste")
			(net "P3V3_AUX")
		)
		(pad "2" smd circle
			(at 0.40005 0 270)
			(size 0 0)
			(layers "F.Cu" "F.Mask" "F.Paste")
			(net "FM_GPU_HSC_EN")
		)
	)
)
